# S9S_MB_2U (Grand Teton) — schematic netlist excerpt (pin names and nets, part order shuffled) for the footprints in the layout excerpt that follows; sources: Cadence DE-HDL packaged netlist, KiCad conversion of 03242023_DA0F0TMBIJ0_F0T_Motherboard_J_brd_V01_OCP.brd

PR330  Q_RES  0 5% CHIP  pkg 0402LF  page 285 : A = PVCCIN_CPU1_VOS1 ; B = PVCCIN_CPU1
C1209  Q_CAP  100PF 50V 5% NPO  pkg 0402  page 220 : A = PWRGD_SYS_PWROK_R ; B = GND

(kicad_pcb
	(version 20260206)
	(generator "pcbnew")
	(generator_version "10.0")
	(general
		(thickness 1.6)
		(legacy_teardrops no)
	)
	(paper "A4")
	(title_block
		(title "03242023_DA0F0TMBIJ0_F0T_Motherboard_J_brd_V01_OCP.brd")
		(comment 1 "Grand Teton / footprints 5970-5971 of 6105")
	)
	(layers
		(0 "F.Cu" signal "TOP")
		(4 "In1.Cu" signal "GND")
		(6 "In2.Cu" signal "IN1")
		(8 "In3.Cu" signal "GND1")
		(10 "In4.Cu" signal "IN2")
		(12 "In5.Cu" signal "GND2")
		(14 "In6.Cu" signal "IN3")
		(16 "In7.Cu" signal "GND3")
		(18 "In8.Cu" signal "VCC")
		(20 "In9.Cu" signal "VCC1")
		(22 "In10.Cu" signal "GND4")
		(24 "In11.Cu" signal "IN4")
		(26 "In12.Cu" signal "GND5")
		(28 "In13.Cu" signal "IN5")
		(30 "In14.Cu" signal "GND6")
		(32 "In15.Cu" signal "IN6")
		(34 "In16.Cu" signal "GND7")
		(2 "B.Cu" signal "BOTTOM")
		(9 "F.Adhes" user "F.Adhesive")
		(11 "B.Adhes" user "B.Adhesive")
		(13 "F.Paste" user "Package Geometry/Pastemask Top")
		(15 "B.Paste" user "Package Geometry/Pastemask Bottom")
		(5 "F.SilkS" user "Ref Des/Silkscreen Top")
		(7 "B.SilkS" user "Ref Des/Silkscreen Bottom")
		(1 "F.Mask" user "Board Geometry/Soldermask Top")
		(3 "B.Mask" user "Board Geometry/Soldermask Bottom")
		(17 "Dwgs.User" user "User.Drawings")
		(19 "Cmts.User" user "User.Comments")
		(21 "Eco1.User" user "User.Eco1")
		(23 "Eco2.User" user "User.Eco2")
		(25 "Edge.Cuts" user "Board Geometry/Outline")
		(27 "Margin" user)
		(31 "F.CrtYd" user "Package Geometry/Place Bound Top")
		(29 "B.CrtYd" user "Package Geometry/Place Bound Bottom")
		(35 "F.Fab" user "Ref Des/Assembly Top")
		(33 "B.Fab" user "Ref Des/Assembly Bottom")
	)
	(footprint ""
		(layer "B.Cu")
		(at 312.090816 -27.320748 -90)
		(property "Reference" "C1209"
			(at 0 0 90)
			(layer "B.SilkS")
			(hide yes)
			(effects
				(font
					(size 1.27 1.27)
				)
				(justify mirror)
			)
		)
		(property "Value" ""
			(at 0 0 90)
			(layer "B.Fab")
			(effects
				(font
					(size 1.27 1.27)
				)
				(justify mirror)
			)
		)
		(duplicate_pad_numbers_are_jumpers no)
		(fp_line
			(start -0.7874 0.4064)
			(end 0.7874 0.4064)
			(stroke
				(width 0.1524)
				(type default)
			)
			(layer "B.SilkS")
		)
		(fp_line
			(start 0.7874 0.4064)
			(end 0.7874 -0.4064)
			(stroke
				(width 0.1524)
				(type default)
			)
			(layer "B.SilkS")
		)
		(fp_line
			(start -0.7874 -0.4064)
			(end -0.7874 0.4064)
			(stroke
				(width 0.1524)
				(type default)
			)
			(layer "B.SilkS")
		)
		(fp_line
			(start 0.7874 -0.4064)
			(end -0.7874 -0.4064)
			(stroke
				(width 0.1524)
				(type default)
			)
			(layer "B.SilkS")
		)
		(fp_line
			(start -0.67945 0.3048)
			(end -0.120396 0.3048)
			(stroke
				(width 0.1)
				(type default)
			)
			(layer "B.Fab")
		)
		(fp_line
			(start -0.120396 0.3048)
			(end -0.120396 0.2794)
			(stroke
				(width 0.1)
				(type default)
			)
			(layer "B.Fab")
		)
		(fp_line
			(start 0.12065 0.3048)
			(end 0.67945 0.3048)
			(stroke
				(width 0.1)
				(type default)
			)
			(layer "B.Fab")
		)
		(fp_line
			(start 0.67945 0.3048)
			(end 0.67945 -0.305054)
			(stroke
				(width 0.1)
				(type default)
			)
			(layer "B.Fab")
		)
		(fp_line
			(start -0.120396 0.2794)
			(end 0.12065 0.2794)
			(stroke
				(width 0.1)
				(type default)
			)
			(layer "B.Fab")
		)
		(fp_line
			(start 0.12065 0.2794)
			(end 0.12065 0.3048)
			(stroke
				(width 0.1)
				(type default)
			)
			(layer "B.Fab")
		)
		(fp_line
			(start -0.12065 -0.2794)
			(end -0.12065 -0.3048)
			(stroke
				(width 0.1)
				(type default)
			)
			(layer "B.Fab")
		)
		(fp_line
			(start 0.12065 -0.2794)
			(end -0.12065 -0.2794)
			(stroke
				(width 0.1)
				(type default)
			)
			(layer "B.Fab")
		)
		(fp_line
			(start -0.67945 -0.3048)
			(end -0.67945 0.3048)
			(stroke
				(width 0.1)
				(type default)
			)
			(layer "B.Fab")
		)
		(fp_line
			(start -0.12065 -0.3048)
			(end -0.67945 -0.3048)
			(stroke
				(width 0.1)
				(type default)
			)
			(layer "B.Fab")
		)
		(fp_line
			(start 0.12065 -0.305054)
			(end 0.12065 -0.2794)
			(stroke
				(width 0.1)
				(type default)
			)
			(layer "B.Fab")
		)
		(fp_line
			(start 0.67945 -0.305054)
			(end 0.12065 -0.305054)
			(stroke
				(width 0.1)
				(type default)
			)
			(layer "B.Fab")
		)
		(pad "1" smd circle
			(at 0.40005 0 90)
			(size 0 0)
			(layers "B.Cu" "B.Mask" "B.Paste")
			(net "PWRGD_SYS_PWROK_R")
		)
		(pad "2" smd circle
			(at -0.40005 0 90)
			(size 0 0)
			(layers "B.Cu" "B.Mask" "B.Paste")
			(net "GND")
		)
	)
	(footprint ""
		(layer "B.Cu")
		(at 93.571314 -336.278474 -90)
		(property "Reference" "PR330"
			(at 0 0 90)
			(layer "B.SilkS")
			(hide yes)
			(effects
				(font
					(size 1.27 1.27)
				)
				(justify mirror)
			)
		)
		(property "Value" ""
			(at 0 0 90)
			(layer "B.Fab")
			(effects
				(font
					(size 1.27 1.27)
				)
				(justify mirror)
			)
		)
		(duplicate_pad_numbers_are_jumpers no)
		(fp_line
			(start -0.7874 0.4064)
			(end 0.7874 0.4064)
			(stroke
				(width 0.1524)
				(type default)
			)
			(layer "B.SilkS")
		)
		(fp_line
			(start 0.7874 0.4064)
			(end 0.7874 -0.4064)
			(stroke
				(width 0.1524)
				(type default)
			)
			(layer "B.SilkS")
		)
		(fp_line
			(start -0.7874 -0.4064)
			(end -0.7874 0.4064)
			(stroke
				(width 0.1524)
				(type default)
			)
			(layer "B.SilkS")
		)
		(fp_line
			(start 0.7874 -0.4064)
			(end -0.7874 -0.4064)
			(stroke
				(width 0.1524)
				(type default)
			)
			(layer "B.SilkS")
		)
		(fp_line
			(start -0.67945 0.3048)
			(end -0.120396 0.3048)
			(stroke
				(width 0.1)
				(type default)
			)
			(layer "B.Fab")
		)
		(fp_line
			(start -0.120396 0.3048)
			(end -0.120396 0.2794)
			(stroke
				(width 0.1)
				(type default)
			)
			(layer "B.Fab")
		)
		(fp_line
			(start 0.12065 0.3048)
			(end 0.67945 0.3048)
			(stroke
				(width 0.1)
				(type default)
			)
			(layer "B.Fab")
		)
		(fp_line
			(start 0.67945 0.3048)
			(end 0.67945 -0.305054)
			(stroke
				(width 0.1)
				(type default)
			)
			(layer "B.Fab")
		)
		(fp_line
			(start -0.120396 0.2794)
			(end 0.12065 0.2794)
			(stroke
				(width 0.1)
				(type default)
			)
			(layer "B.Fab")
		)
		(fp_line
			(start 0.12065 0.2794)
			(end 0.12065 0.3048)
			(stroke
				(width 0.1)
				(type default)
			)
			(layer "B.Fab")
		)
		(fp_line
			(start -0.12065 -0.2794)
			(end -0.12065 -0.3048)
			(stroke
				(width 0.1)
				(type default)
			)
			(layer "B.Fab")
		)
		(fp_line
			(start 0.12065 -0.2794)
			(end -0.12065 -0.2794)
			(stroke
				(width 0.1)
				(type default)
			)
			(layer "B.Fab")
		)
		(fp_line
			(start -0.67945 -0.3048)
			(end -0.67945 0.3048)
			(stroke
				(width 0.1)
				(type default)
			)
			(layer "B.Fab")
		)
		(fp_line
			(start -0.12065 -0.3048)
			(end -0.67945 -0.3048)
			(stroke
				(width 0.1)
				(type default)
			)
			(layer "B.Fab")
		)
		(fp_line
			(start 0.12065 -0.305054)
			(end 0.12065 -0.2794)
			(stroke
				(width 0.1)
				(type default)
			)
			(layer "B.Fab")
		)
		(fp_line
			(start 0.67945 -0.305054)
			(end 0.12065 -0.305054)
			(stroke
				(width 0.1)
				(type default)
			)
			(layer "B.Fab")
		)
		(pad "1" smd circle
			(at 0.40005 0 90)
			(size 0 0)
			(layers "B.Cu" "B.Mask" "B.Paste")
			(net "PVCCIN_CPU1_VOS1")
		)
		(pad "2" smd circle
			(at -0.40005 0 90)
			(size 0 0)
			(layers "B.Cu" "B.Mask" "B.Paste")
			(net "PVCCIN_CPU1")
		)
	)
)
